(kicad_pcb
	(version 20260206)
	(generator "pcbnew")
	(generator_version "10.0")
	(general
		(thickness 1.6)
		(legacy_teardrops no)
	)
	(paper "A4")
	(title_block
		(title "01162023_DA0F0TEBIF0_F0T_Expander_BD_F_brd_V02_OCP.brd")
		(comment 1 "Grand Teton / footprints 4589-4595 of 9728")
	)
	(layers
		(0 "F.Cu" signal "TOP")
		(4 "In1.Cu" signal "GND")
		(6 "In2.Cu" signal "VCC")
		(8 "In3.Cu" signal "VCC1")
		(10 "In4.Cu" signal "GND1")
		(12 "In5.Cu" signal "IN1")
		(14 "In6.Cu" signal "GND2")
		(16 "In7.Cu" signal "IN2")
		(18 "In8.Cu" signal "GND3")
		(20 "In9.Cu" signal "IN3")
		(22 "In10.Cu" signal "GND4")
		(24 "In11.Cu" signal "IN4")
		(26 "In12.Cu" signal "GND5")
		(28 "In13.Cu" signal "IN5")
		(30 "In14.Cu" signal "GND6")
		(32 "In15.Cu" signal "IN6")
		(34 "In16.Cu" signal "GND7")
		(2 "B.Cu" signal "BOTTOM")
		(9 "F.Adhes" user "F.Adhesive")
		(11 "B.Adhes" user "B.Adhesive")
		(13 "F.Paste" user "Package Geometry/Pastemask Top")
		(15 "B.Paste" user "Package Geometry/Pastemask Bottom")
		(5 "F.SilkS" user "Ref Des/Silkscreen Top")
		(7 "B.SilkS" user "Ref Des/Silkscreen Bottom")
		(1 "F.Mask" user "Board Geometry/Soldermask Top")
		(3 "B.Mask" user "Board Geometry/Soldermask Bottom")
		(17 "Dwgs.User" user "User.Drawings")
		(19 "Cmts.User" user "User.Comments")
		(21 "Eco1.User" user "User.Eco1")
		(23 "Eco2.User" user "User.Eco2")
		(25 "Edge.Cuts" user "Board Geometry/Outline")
		(27 "Margin" user)
		(31 "F.CrtYd" user "Package Geometry/Place Bound Top")
		(29 "B.CrtYd" user "Package Geometry/Place Bound Bottom")
		(35 "F.Fab" user "Ref Des/Assembly Top")
		(33 "B.Fab" user "Ref Des/Assembly Bottom")
	)
	(footprint ""
		(layer "F.Cu")
		(at 238.919512 -234.728004 -90)
		(property "Reference" "R6182"
			(at 0 0 270)
			(layer "F.SilkS")
			(hide yes)
			(effects
				(font
					(size 1.27 1.27)
				)
			)
		)
		(property "Value" ""
			(at 0 0 270)
			(layer "F.Fab")
			(effects
				(font
					(size 1.27 1.27)
				)
			)
		)
		(duplicate_pad_numbers_are_jumpers no)
		(fp_line
			(start -0.7874 0.4064)
			(end -0.7874 -0.4064)
			(stroke
				(width 0.1524)
				(type default)
			)
			(layer "F.SilkS")
		)
		(fp_line
			(start 0.7874 0.4064)
			(end -0.7874 0.4064)
			(stroke
				(width 0.1524)
				(type default)
			)
			(layer "F.SilkS")
		)
		(fp_line
			(start -0.7874 -0.4064)
			(end 0.7874 -0.4064)
			(stroke
				(width 0.1524)
				(type default)
			)
			(layer "F.SilkS")
		)
		(fp_line
			(start 0.7874 -0.4064)
			(end 0.7874 0.4064)
			(stroke
				(width 0.1524)
				(type default)
			)
			(layer "F.SilkS")
		)
		(fp_line
			(start -0.67945 0.3048)
			(end -0.67945 -0.305054)
			(stroke
				(width 0.1)
				(type default)
			)
			(layer "F.Fab")
		)
		(fp_line
			(start -0.12065 0.3048)
			(end -0.67945 0.3048)
			(stroke
				(width 0.1)
				(type default)
			)
			(layer "F.Fab")
		)
		(fp_line
			(start 0.120396 0.3048)
			(end 0.120396 0.2794)
			(stroke
				(width 0.1)
				(type default)
			)
			(layer "F.Fab")
		)
		(fp_line
			(start 0.67945 0.3048)
			(end 0.120396 0.3048)
			(stroke
				(width 0.1)
				(type default)
			)
			(layer "F.Fab")
		)
		(fp_line
			(start -0.12065 0.2794)
			(end -0.12065 0.3048)
			(stroke
				(width 0.1)
				(type default)
			)
			(layer "F.Fab")
		)
		(fp_line
			(start 0.120396 0.2794)
			(end -0.12065 0.2794)
			(stroke
				(width 0.1)
				(type default)
			)
			(layer "F.Fab")
		)
		(fp_line
			(start -0.12065 -0.2794)
			(end 0.12065 -0.2794)
			(stroke
				(width 0.1)
				(type default)
			)
			(layer "F.Fab")
		)
		(fp_line
			(start 0.12065 -0.2794)
			(end 0.12065 -0.3048)
			(stroke
				(width 0.1)
				(type default)
			)
			(layer "F.Fab")
		)
		(fp_line
			(start 0.12065 -0.3048)
			(end 0.67945 -0.3048)
			(stroke
				(width 0.1)
				(type default)
			)
			(layer "F.Fab")
		)
		(fp_line
			(start 0.67945 -0.3048)
			(end 0.67945 0.3048)
			(stroke
				(width 0.1)
				(type default)
			)
			(layer "F.Fab")
		)
		(fp_line
			(start -0.67945 -0.305054)
			(end -0.12065 -0.305054)
			(stroke
				(width 0.1)
				(type default)
			)
			(layer "F.Fab")
		)
		(fp_line
			(start -0.12065 -0.305054)
			(end -0.12065 -0.2794)
			(stroke
				(width 0.1)
				(type default)
			)
			(layer "F.Fab")
		)
		(pad "1" smd circle
			(at -0.40005 0 270)
			(size 0 0)
			(layers "F.Cu" "F.Mask" "F.Paste")
			(net "GND")
		)
		(pad "2" smd circle
			(at 0.40005 0 270)
			(size 0 0)
			(layers "F.Cu" "F.Mask" "F.Paste")
			(net "SSD0_PWRDIS_BIC_R")
		)
	)
	(footprint ""
		(layer "F.Cu")
		(at 352.320098 -159.465518 180)
		(property "Reference" "R4826"
			(at 0 0 180)
			(layer "F.SilkS")
			(hide yes)
			(effects
				(font
					(size 1.27 1.27)
				)
			)
		)
		(property "Value" ""
			(at 0 0 180)
			(layer "F.Fab")
			(effects
				(font
					(size 1.27 1.27)
				)
			)
		)
		(duplicate_pad_numbers_are_jumpers no)
		(fp_line
			(start 0.7874 0.4064)
			(end -0.7874 0.4064)
			(stroke
				(width 0.1524)
				(type default)
			)
			(layer "F.SilkS")
		)
		(fp_line
			(start 0.7874 -0.4064)
			(end 0.7874 0.4064)
			(stroke
				(width 0.1524)
				(type default)
			)
			(layer "F.SilkS")
		)
		(fp_line
			(start -0.7874 0.4064)
			(end -0.7874 -0.4064)
			(stroke
				(width 0.1524)
				(type default)
			)
			(layer "F.SilkS")
		)
		(fp_line
			(start -0.7874 -0.4064)
			(end 0.7874 -0.4064)
			(stroke
				(width 0.1524)
				(type default)
			)
			(layer "F.SilkS")
		)
		(fp_line
			(start 0.67945 0.3048)
			(end 0.120396 0.3048)
			(stroke
				(width 0.1)
				(type default)
			)
			(layer "F.Fab")
		)
		(fp_line
			(start 0.67945 -0.3048)
			(end 0.67945 0.3048)
			(stroke
				(width 0.1)
				(type default)
			)
			(layer "F.Fab")
		)
		(fp_line
			(start 0.12065 -0.2794)
			(end 0.12065 -0.3048)
			(stroke
				(width 0.1)
				(type default)
			)
			(layer "F.Fab")
		)
		(fp_line
			(start 0.12065 -0.3048)
			(end 0.67945 -0.3048)
			(stroke
				(width 0.1)
				(type default)
			)
			(layer "F.Fab")
		)
		(fp_line
			(start 0.120396 0.3048)
			(end 0.120396 0.2794)
			(stroke
				(width 0.1)
				(type default)
			)
			(layer "F.Fab")
		)
		(fp_line
			(start 0.120396 0.2794)
			(end -0.12065 0.2794)
			(stroke
				(width 0.1)
				(type default)
			)
			(layer "F.Fab")
		)
		(fp_line
			(start -0.12065 0.3048)
			(end -0.67945 0.3048)
			(stroke
				(width 0.1)
				(type default)
			)
			(layer "F.Fab")
		)
		(fp_line
			(start -0.12065 0.2794)
			(end -0.12065 0.3048)
			(stroke
				(width 0.1)
				(type default)
			)
			(layer "F.Fab")
		)
		(fp_line
			(start -0.12065 -0.2794)
			(end 0.12065 -0.2794)
			(stroke
				(width 0.1)
				(type default)
			)
			(layer "F.Fab")
		)
		(fp_line
			(start -0.12065 -0.305054)
			(end -0.12065 -0.2794)
			(stroke
				(width 0.1)
				(type default)
			)
			(layer "F.Fab")
		)
		(fp_line
			(start -0.67945 0.3048)
			(end -0.67945 -0.305054)
			(stroke
				(width 0.1)
				(type default)
			)
			(layer "F.Fab")
		)
		(fp_line
			(start -0.67945 -0.305054)
			(end -0.12065 -0.305054)
			(stroke
				(width 0.1)
				(type default)
			)
			(layer "F.Fab")
		)
		(pad "1" smd circle
			(at -0.40005 0 180)
			(size 0 0)
			(layers "F.Cu" "F.Mask" "F.Paste")
			(net "GND")
		)
		(pad "2" smd circle
			(at 0.40005 0 180)
			(size 0 0)
			(layers "F.Cu" "F.Mask" "F.Paste")
			(net "PCA9555_0_PEX3_A0")
		)
	)
	(footprint ""
		(layer "F.Cu")
		(at 366.979962 -135.62711 90)
		(property "Reference" "PD98"
			(at -3.49631 2.184908 90)
			(unlocked yes)
			(layer "F.SilkS")
			(effects
				(font
					(size 0.7874 0.5842)
					(thickness 0.1524)
				)
				(justify left)
			)
		)
		(property "Value" ""
			(at 0 0 90)
			(layer "F.Fab")
			(effects
				(font
					(size 1.27 1.27)
				)
			)
		)
		(duplicate_pad_numbers_are_jumpers no)
		(fp_line
			(start 4.107942 -1.459992)
			(end 4.107942 1.459992)
			(stroke
				(width 0.1524)
				(type default)
			)
			(layer "F.SilkS")
		)
		(fp_line
			(start -3.400044 -1.459992)
			(end 4.107942 -1.459992)
			(stroke
				(width 0.1524)
				(type default)
			)
			(layer "F.SilkS")
		)
		(fp_line
			(start 4.107942 1.459992)
			(end -3.400044 1.459992)
			(stroke
				(width 0.1524)
				(type default)
			)
			(layer "F.SilkS")
		)
		(fp_line
			(start -3.400044 1.459992)
			(end -3.400044 -1.459992)
			(stroke
				(width 0.1524)
				(type default)
			)
			(layer "F.SilkS")
		)
		(fp_poly
			(pts
				(xy 4.107942 -1.459992) (xy 4.107942 1.459992) (xy 3.308096 1.459992) (xy 3.308096 -1.459992)
			)
			(stroke
				(width 0)
				(type default)
			)
			(fill yes)
			(layer "F.SilkS")
		)
		(fp_line
			(start 2.29997 -1.459992)
			(end 2.29997 1.459992)
			(stroke
				(width 0.1)
				(type default)
			)
			(layer "F.Fab")
		)
		(fp_line
			(start -2.29997 -1.459992)
			(end 2.29997 -1.459992)
			(stroke
				(width 0.1)
				(type default)
			)
			(layer "F.Fab")
		)
		(fp_line
			(start 2.29997 1.459992)
			(end -2.29997 1.459992)
			(stroke
				(width 0.1)
				(type default)
			)
			(layer "F.Fab")
		)
		(fp_line
			(start -2.29997 1.459992)
			(end -2.29997 -1.459992)
			(stroke
				(width 0.1)
				(type default)
			)
			(layer "F.Fab")
		)
		(fp_text user "+"
			(at -4.7752 -0.12065 90)
			(unlocked yes)
			(layer "F.SilkS")
			(effects
				(font
					(size 1.905 1.4224)
					(thickness 0.1524)
				)
				(justify left)
			)
		)
		(fp_text user "-"
			(at 3.631438 2.56032 270)
			(unlocked yes)
			(layer "F.SilkS")
			(effects
				(font
					(size 1.905 1.4224)
					(thickness 0.1524)
				)
				(justify left)
			)
		)
		(fp_text user "+"
			(at -4.7752 -0.12065 90)
			(unlocked yes)
			(layer "F.Fab")
			(effects
				(font
					(size 1.905 1.4224)
					(thickness 0.1524)
				)
				(justify left)
			)
		)
		(fp_text user "-"
			(at 5.4102 0.29845 270)
			(unlocked yes)
			(layer "F.Fab")
			(effects
				(font
					(size 1.905 1.4224)
					(thickness 0.1524)
				)
				(justify left)
			)
		)
		(pad "A" smd rect
			(at -1.999996 0 180)
			(size 1.7018 2.5146)
			(layers "F.Cu" "F.Mask" "F.Paste")
			(net "GND")
		)
		(pad "C" smd rect
			(at 1.999996 0 180)
			(size 1.7018 2.5146)
			(layers "F.Cu" "F.Mask" "F.Paste")
			(net "P12V_NIC6_R")
		)
	)
	(footprint ""
		(layer "F.Cu")
		(at 381.41148 -258.234434)
		(property "Reference" "L141"
			(at 0 0 0)
			(layer "F.SilkS")
			(hide yes)
			(effects
				(font
					(size 1.27 1.27)
				)
			)
		)
		(property "Value" ""
			(at 0 0 0)
			(layer "F.Fab")
			(effects
				(font
					(size 1.27 1.27)
				)
			)
		)
		(duplicate_pad_numbers_are_jumpers no)
		(fp_line
			(start -1.63576 -0.8128)
			(end -1.63576 0.8128)
			(stroke
				(width 0.1524)
				(type default)
			)
			(layer "F.SilkS")
		)
		(fp_line
			(start -1.63576 -0.8128)
			(end 1.63576 -0.8128)
			(stroke
				(width 0.1524)
				(type default)
			)
			(layer "F.SilkS")
		)
		(fp_line
			(start 1.63576 -0.8128)
			(end 1.63576 0.8128)
			(stroke
				(width 0.1524)
				(type default)
			)
			(layer "F.SilkS")
		)
		(fp_line
			(start 1.63576 0.8128)
			(end -1.63576 0.8128)
			(stroke
				(width 0.1524)
				(type default)
			)
			(layer "F.SilkS")
		)
		(fp_line
			(start -1.56083 -0.738632)
			(end -1.56083 0.7366)
			(stroke
				(width 0.1)
				(type default)
			)
			(layer "F.Fab")
		)
		(fp_line
			(start -1.56083 0.7366)
			(end -1.524 0.7366)
			(stroke
				(width 0.1)
				(type default)
			)
			(layer "F.Fab")
		)
		(fp_line
			(start -1.524 0.7366)
			(end 1.524 0.7366)
			(stroke
				(width 0.1)
				(type default)
			)
			(layer "F.Fab")
		)
		(fp_line
			(start 1.524 0.7366)
			(end 1.560576 0.7366)
			(stroke
				(width 0.1)
				(type default)
			)
			(layer "F.Fab")
		)
		(fp_line
			(start 1.560576 -0.738632)
			(end -1.56083 -0.738632)
			(stroke
				(width 0.1)
				(type default)
			)
			(layer "F.Fab")
		)
		(fp_line
			(start 1.560576 0.7366)
			(end 1.560576 -0.738632)
			(stroke
				(width 0.1)
				(type default)
			)
			(layer "F.Fab")
		)
		(pad "1" smd rect
			(at -0.94996 0 180)
			(size 1.1176 1.3716)
			(layers "F.Cu" "F.Mask" "F.Paste")
			(net "P1V8_PLL0_PEX3")
		)
		(pad "2" smd rect
			(at 0.94996 0 180)
			(size 1.1176 1.3716)
			(layers "F.Cu" "F.Mask" "F.Paste")
			(net "PCEPLL5_VDDA18_PEX3")
		)
	)
	(footprint ""
		(layer "F.Cu")
		(at 82.661506 -155.196794 180)
		(property "Reference" "C2"
			(at 0 0 180)
			(layer "F.SilkS")
			(hide yes)
			(effects
				(font
					(size 1.27 1.27)
				)
			)
		)
		(property "Value" ""
			(at 0 0 180)
			(layer "F.Fab")
			(effects
				(font
					(size 1.27 1.27)
				)
			)
		)
		(duplicate_pad_numbers_are_jumpers no)
		(fp_line
			(start 0.299974 0.150114)
			(end -0.299974 0.150114)
			(stroke
				(width 0.1)
				(type default)
			)
			(layer "F.Fab")
		)
		(fp_line
			(start 0.299974 -0.150114)
			(end 0.299974 0.150114)
			(stroke
				(width 0.1)
				(type default)
			)
			(layer "F.Fab")
		)
		(fp_line
			(start -0.299974 0.150114)
			(end -0.299974 -0.150114)
			(stroke
				(width 0.1)
				(type default)
			)
			(layer "F.Fab")
		)
		(fp_line
			(start -0.299974 -0.150114)
			(end 0.299974 -0.150114)
			(stroke
				(width 0.1)
				(type default)
			)
			(layer "F.Fab")
		)
		(pad "1" smd rect
			(at -0.2667 0 180)
			(size 0.3048 0.381)
			(layers "F.Cu" "F.Mask" "F.Paste")
			(net "P5E_PEX0_STN0_TX_DN<15>")
		)
		(pad "2" smd rect
			(at 0.2667 0 180)
			(size 0.3048 0.381)
			(layers "F.Cu" "F.Mask" "F.Paste")
			(net "P5E_PEX0_STN0_TX_C_DN<15>")
		)
	)
	(footprint ""
		(layer "F.Cu")
		(at 310.467756 -52.035456 180)
		(property "Reference" "R873"
			(at 0 0 180)
			(layer "F.SilkS")
			(hide yes)
			(effects
				(font
					(size 1.27 1.27)
				)
			)
		)
		(property "Value" ""
			(at 0 0 180)
			(layer "F.Fab")
			(effects
				(font
					(size 1.27 1.27)
				)
			)
		)
		(duplicate_pad_numbers_are_jumpers no)
		(fp_line
			(start 0.7874 0.4064)
			(end -0.7874 0.4064)
			(stroke
				(width 0.1524)
				(type default)
			)
			(layer "F.SilkS")
		)
		(fp_line
			(start 0.7874 -0.4064)
			(end 0.7874 0.4064)
			(stroke
				(width 0.1524)
				(type default)
			)
			(layer "F.SilkS")
		)
		(fp_line
			(start -0.7874 0.4064)
			(end -0.7874 -0.4064)
			(stroke
				(width 0.1524)
				(type default)
			)
			(layer "F.SilkS")
		)
		(fp_line
			(start -0.7874 -0.4064)
			(end 0.7874 -0.4064)
			(stroke
				(width 0.1524)
				(type default)
			)
			(layer "F.SilkS")
		)
		(fp_line
			(start 0.67945 0.3048)
			(end 0.120396 0.3048)
			(stroke
				(width 0.1)
				(type default)
			)
			(layer "F.Fab")
		)
		(fp_line
			(start 0.67945 -0.3048)
			(end 0.67945 0.3048)
			(stroke
				(width 0.1)
				(type default)
			)
			(layer "F.Fab")
		)
		(fp_line
			(start 0.12065 -0.2794)
			(end 0.12065 -0.3048)
			(stroke
				(width 0.1)
				(type default)
			)
			(layer "F.Fab")
		)
		(fp_line
			(start 0.12065 -0.3048)
			(end 0.67945 -0.3048)
			(stroke
				(width 0.1)
				(type default)
			)
			(layer "F.Fab")
		)
		(fp_line
			(start 0.120396 0.3048)
			(end 0.120396 0.2794)
			(stroke
				(width 0.1)
				(type default)
			)
			(layer "F.Fab")
		)
		(fp_line
			(start 0.120396 0.2794)
			(end -0.12065 0.2794)
			(stroke
				(width 0.1)
				(type default)
			)
			(layer "F.Fab")
		)
		(fp_line
			(start -0.12065 0.3048)
			(end -0.67945 0.3048)
			(stroke
				(width 0.1)
				(type default)
			)
			(layer "F.Fab")
		)
		(fp_line
			(start -0.12065 0.2794)
			(end -0.12065 0.3048)
			(stroke
				(width 0.1)
				(type default)
			)
			(layer "F.Fab")
		)
		(fp_line
			(start -0.12065 -0.2794)
			(end 0.12065 -0.2794)
			(stroke
				(width 0.1)
				(type default)
			)
			(layer "F.Fab")
		)
		(fp_line
			(start -0.12065 -0.305054)
			(end -0.12065 -0.2794)
			(stroke
				(width 0.1)
				(type default)
			)
			(layer "F.Fab")
		)
		(fp_line
			(start -0.67945 0.3048)
			(end -0.67945 -0.305054)
			(stroke
				(width 0.1)
				(type default)
			)
			(layer "F.Fab")
		)
		(fp_line
			(start -0.67945 -0.305054)
			(end -0.12065 -0.305054)
			(stroke
				(width 0.1)
				(type default)
			)
			(layer "F.Fab")
		)
		(pad "1" smd circle
			(at -0.40005 0 180)
			(size 0 0)
			(layers "F.Cu" "F.Mask" "F.Paste")
			(net "P3V3_AUX")
		)
		(pad "2" smd circle
			(at 0.40005 0 180)
			(size 0 0)
			(layers "F.Cu" "F.Mask" "F.Paste")
			(net "PWRGD_P12V_SSD10")
		)
	)
	(footprint ""
		(layer "F.Cu")
		(at 407.295096 -96.702372 180)
		(property "Reference" "R404"
			(at 0 0 180)
			(layer "F.SilkS")
			(hide yes)
			(effects
				(font
					(size 1.27 1.27)
				)
			)
		)
		(property "Value" ""
			(at 0 0 180)
			(layer "F.Fab")
			(effects
				(font
					(size 1.27 1.27)
				)
			)
		)
		(duplicate_pad_numbers_are_jumpers no)
		(fp_line
			(start 0.7874 0.4064)
			(end -0.7874 0.4064)
			(stroke
				(width 0.1524)
				(type default)
			)
			(layer "F.SilkS")
		)
		(fp_line
			(start 0.7874 -0.4064)
			(end 0.7874 0.4064)
			(stroke
				(width 0.1524)
				(type default)
			)
			(layer "F.SilkS")
		)
		(fp_line
			(start -0.7874 0.4064)
			(end -0.7874 -0.4064)
			(stroke
				(width 0.1524)
				(type default)
			)
			(layer "F.SilkS")
		)
		(fp_line
			(start -0.7874 -0.4064)
			(end 0.7874 -0.4064)
			(stroke
				(width 0.1524)
				(type default)
			)
			(layer "F.SilkS")
		)
		(fp_line
			(start 0.67945 0.3048)
			(end 0.120396 0.3048)
			(stroke
				(width 0.1)
				(type default)
			)
			(layer "F.Fab")
		)
		(fp_line
			(start 0.67945 -0.3048)
			(end 0.67945 0.3048)
			(stroke
				(width 0.1)
				(type default)
			)
			(layer "F.Fab")
		)
		(fp_line
			(start 0.12065 -0.2794)
			(end 0.12065 -0.3048)
			(stroke
				(width 0.1)
				(type default)
			)
			(layer "F.Fab")
		)
		(fp_line
			(start 0.12065 -0.3048)
			(end 0.67945 -0.3048)
			(stroke
				(width 0.1)
				(type default)
			)
			(layer "F.Fab")
		)
		(fp_line
			(start 0.120396 0.3048)
			(end 0.120396 0.2794)
			(stroke
				(width 0.1)
				(type default)
			)
			(layer "F.Fab")
		)
		(fp_line
			(start 0.120396 0.2794)
			(end -0.12065 0.2794)
			(stroke
				(width 0.1)
				(type default)
			)
			(layer "F.Fab")
		)
		(fp_line
			(start -0.12065 0.3048)
			(end -0.67945 0.3048)
			(stroke
				(width 0.1)
				(type default)
			)
			(layer "F.Fab")
		)
		(fp_line
			(start -0.12065 0.2794)
			(end -0.12065 0.3048)
			(stroke
				(width 0.1)
				(type default)
			)
			(layer "F.Fab")
		)
		(fp_line
			(start -0.12065 -0.2794)
			(end 0.12065 -0.2794)
			(stroke
				(width 0.1)
				(type default)
			)
			(layer "F.Fab")
		)
		(fp_line
			(start -0.12065 -0.305054)
			(end -0.12065 -0.2794)
			(stroke
				(width 0.1)
				(type default)
			)
			(layer "F.Fab")
		)
		(fp_line
			(start -0.67945 0.3048)
			(end -0.67945 -0.305054)
			(stroke
				(width 0.1)
				(type default)
			)
			(layer "F.Fab")
		)
		(fp_line
			(start -0.67945 -0.305054)
			(end -0.12065 -0.305054)
			(stroke
				(width 0.1)
				(type default)
			)
			(layer "F.Fab")
		)
		(pad "1" smd circle
			(at -0.40005 0 180)
			(size 0 0)
			(layers "F.Cu" "F.Mask" "F.Paste")
			(net "RST_NIC7_PERST2_R_N")
		)
		(pad "2" smd circle
			(at 0.40005 0 180)
			(size 0 0)
			(layers "F.Cu" "F.Mask" "F.Paste")
			(net "RST_HP_NIC7_BUF_N")
		)
	)
)
